# SCM (Grand Teton) — schematic netlist excerpt (pin names and nets, part order shuffled) for the footprints in the layout excerpt that follows; sources: Cadence DE-HDL packaged netlist, KiCad conversion of 12092022_DA0F0TMDCD0_F0T_Management_Board_D_brd_V3_OCP.brd

U8  74LVC1G126SE7  74LVC1G126SE-7 IC  pkg SOT353_0-65_2X1-25  page 49
  OE  = BMC_ID_BEEP_SEL
  A  = PCH_BEEP_LED
  GND  = GND
  Y  = BEEP_LED
  VCC  = P3V3_AUX

R642  Q_RES  100K 1% CHIP  pkg 0402LF  page 42 : A = GND ; B = FM_JTAG_BMC_MUX_SEL

(kicad_pcb
	(version 20260206)
	(generator "pcbnew")
	(generator_version "10.0")
	(general
		(thickness 1.6)
		(legacy_teardrops no)
	)
	(paper "A4")
	(title_block
		(title "12092022_DA0F0TMDCD0_F0T_Management_Board_D_brd_V3_OCP.brd")
		(comment 1 "Grand Teton / footprints 1014-1015 of 1440")
	)
	(layers
		(0 "F.Cu" signal "TOP")
		(4 "In1.Cu" signal "GND")
		(6 "In2.Cu" signal "IN1")
		(8 "In3.Cu" signal "GND1")
		(10 "In4.Cu" signal "IN2")
		(12 "In5.Cu" signal "VCC")
		(14 "In6.Cu" signal "VCC1")
		(16 "In7.Cu" signal "IN3")
		(18 "In8.Cu" signal "GND2")
		(20 "In9.Cu" signal "IN4")
		(22 "In10.Cu" signal "GND3")
		(2 "B.Cu" signal "BOTTOM")
		(9 "F.Adhes" user "F.Adhesive")
		(11 "B.Adhes" user "B.Adhesive")
		(13 "F.Paste" user "Package Geometry/Pastemask Top")
		(15 "B.Paste" user "Package Geometry/Pastemask Bottom")
		(5 "F.SilkS" user "Ref Des/Silkscreen Top")
		(7 "B.SilkS" user "Ref Des/Silkscreen Bottom")
		(1 "F.Mask" user "Board Geometry/Soldermask Top")
		(3 "B.Mask" user "Board Geometry/Soldermask Bottom")
		(17 "Dwgs.User" user "User.Drawings")
		(19 "Cmts.User" user "User.Comments")
		(21 "Eco1.User" user "User.Eco1")
		(23 "Eco2.User" user "User.Eco2")
		(25 "Edge.Cuts" user "Board Geometry/Outline")
		(27 "Margin" user)
		(31 "F.CrtYd" user "Package Geometry/Place Bound Top")
		(29 "B.CrtYd" user "Package Geometry/Place Bound Bottom")
		(35 "F.Fab" user "Ref Des/Assembly Top")
		(33 "B.Fab" user "Ref Des/Assembly Bottom")
	)
	(footprint ""
		(layer "B.Cu")
		(at 14.224 -24.13 -90)
		(property "Reference" "U8"
			(at 1.31826 1.352296 0)
			(unlocked yes)
			(layer "B.SilkS")
			(effects
				(font
					(size 0.7874 0.5842)
					(thickness 0.1524)
				)
				(justify left mirror)
			)
		)
		(property "Value" ""
			(at 0 0 90)
			(layer "B.Fab")
			(effects
				(font
					(size 1.27 1.27)
				)
				(justify mirror)
			)
		)
		(duplicate_pad_numbers_are_jumpers no)
		(fp_line
			(start -1.400048 1.100074)
			(end 1.400048 1.100074)
			(stroke
				(width 0.1524)
				(type default)
			)
			(layer "B.SilkS")
		)
		(fp_line
			(start 1.400048 1.100074)
			(end 1.400048 -1.100074)
			(stroke
				(width 0.1524)
				(type default)
			)
			(layer "B.SilkS")
		)
		(fp_line
			(start -1.400048 -1.100074)
			(end -1.400048 1.100074)
			(stroke
				(width 0.1524)
				(type default)
			)
			(layer "B.SilkS")
		)
		(fp_line
			(start -1.400048 -1.100074)
			(end 1.400048 -1.100074)
			(stroke
				(width 0.1524)
				(type default)
			)
			(layer "B.SilkS")
		)
		(fp_poly
			(pts
				(xy 1.029208 -1.283716) (xy 0.521208 -2.299716) (xy 1.537208 -2.299716)
			)
			(stroke
				(width 0)
				(type default)
			)
			(fill yes)
			(layer "B.SilkS")
		)
		(fp_line
			(start -0.674878 1.100074)
			(end 0.674878 1.100074)
			(stroke
				(width 0.1)
				(type default)
			)
			(layer "B.Fab")
		)
		(fp_line
			(start 0.674878 1.100074)
			(end 0.674878 -1.100074)
			(stroke
				(width 0.1)
				(type default)
			)
			(layer "B.Fab")
		)
		(fp_line
			(start -0.674878 -1.100074)
			(end -0.674878 1.100074)
			(stroke
				(width 0.1)
				(type default)
			)
			(layer "B.Fab")
		)
		(fp_line
			(start 0.674878 -1.100074)
			(end -0.674878 -1.100074)
			(stroke
				(width 0.1)
				(type default)
			)
			(layer "B.Fab")
		)
		(fp_poly
			(pts
				(xy 1.590548 -0.649986) (xy 2.606548 -1.157986) (xy 2.606548 -0.141986)
			)
			(stroke
				(width 0)
				(type default)
			)
			(fill yes)
			(layer "B.Fab")
		)
		(pad "1" smd rect
			(at 0.94996 -0.649986 180)
			(size 0.4318 0.6096)
			(layers "B.Cu" "B.Mask" "B.Paste")
			(net "BMC_ID_BEEP_SEL")
		)
		(pad "2" smd rect
			(at 0.94996 0 180)
			(size 0.4318 0.6096)
			(layers "B.Cu" "B.Mask" "B.Paste")
			(net "PCH_BEEP_LED")
		)
		(pad "3" smd rect
			(at 0.94996 0.649986 180)
			(size 0.4318 0.6096)
			(layers "B.Cu" "B.Mask" "B.Paste")
			(net "GND")
		)
		(pad "4" smd rect
			(at -0.94996 0.649986 180)
			(size 0.4318 0.6096)
			(layers "B.Cu" "B.Mask" "B.Paste")
			(net "BEEP_LED")
		)
		(pad "5" smd rect
			(at -0.94996 -0.649986 180)
			(size 0.4318 0.6096)
			(layers "B.Cu" "B.Mask" "B.Paste")
			(net "P3V3_AUX")
		)
	)
	(footprint ""
		(layer "B.Cu")
		(at 38.608 -66.421 90)
		(property "Reference" "R642"
			(at 0 0 90)
			(layer "B.SilkS")
			(hide yes)
			(effects
				(font
					(size 1.27 1.27)
				)
				(justify mirror)
			)
		)
		(property "Value" ""
			(at 0 0 90)
			(layer "B.Fab")
			(effects
				(font
					(size 1.27 1.27)
				)
				(justify mirror)
			)
		)
		(duplicate_pad_numbers_are_jumpers no)
		(fp_line
			(start 0.7874 -0.4064)
			(end -0.7874 -0.4064)
			(stroke
				(width 0.1524)
				(type default)
			)
			(layer "B.SilkS")
		)
		(fp_line
			(start -0.7874 -0.4064)
			(end -0.7874 0.4064)
			(stroke
				(width 0.1524)
				(type default)
			)
			(layer "B.SilkS")
		)
		(fp_line
			(start 0.7874 0.4064)
			(end 0.7874 -0.4064)
			(stroke
				(width 0.1524)
				(type default)
			)
			(layer "B.SilkS")
		)
		(fp_line
			(start -0.7874 0.4064)
			(end 0.7874 0.4064)
			(stroke
				(width 0.1524)
				(type default)
			)
			(layer "B.SilkS")
		)
		(fp_line
			(start 0.67945 -0.305054)
			(end 0.12065 -0.305054)
			(stroke
				(width 0.1)
				(type default)
			)
			(layer "B.Fab")
		)
		(fp_line
			(start 0.12065 -0.305054)
			(end 0.12065 -0.2794)
			(stroke
				(width 0.1)
				(type default)
			)
			(layer "B.Fab")
		)
		(fp_line
			(start -0.12065 -0.3048)
			(end -0.67945 -0.3048)
			(stroke
				(width 0.1)
				(type default)
			)
			(layer "B.Fab")
		)
		(fp_line
			(start -0.67945 -0.3048)
			(end -0.67945 0.3048)
			(stroke
				(width 0.1)
				(type default)
			)
			(layer "B.Fab")
		)
		(fp_line
			(start 0.12065 -0.2794)
			(end -0.12065 -0.2794)
			(stroke
				(width 0.1)
				(type default)
			)
			(layer "B.Fab")
		)
		(fp_line
			(start -0.12065 -0.2794)
			(end -0.12065 -0.3048)
			(stroke
				(width 0.1)
				(type default)
			)
			(layer "B.Fab")
		)
		(fp_line
			(start 0.12065 0.2794)
			(end 0.12065 0.3048)
			(stroke
				(width 0.1)
				(type default)
			)
			(layer "B.Fab")
		)
		(fp_line
			(start -0.120396 0.2794)
			(end 0.12065 0.2794)
			(stroke
				(width 0.1)
				(type default)
			)
			(layer "B.Fab")
		)
		(fp_line
			(start 0.67945 0.3048)
			(end 0.67945 -0.305054)
			(stroke
				(width 0.1)
				(type default)
			)
			(layer "B.Fab")
		)
		(fp_line
			(start 0.12065 0.3048)
			(end 0.67945 0.3048)
			(stroke
				(width 0.1)
				(type default)
			)
			(layer "B.Fab")
		)
		(fp_line
			(start -0.120396 0.3048)
			(end -0.120396 0.2794)
			(stroke
				(width 0.1)
				(type default)
			)
			(layer "B.Fab")
		)
		(fp_line
			(start -0.67945 0.3048)
			(end -0.120396 0.3048)
			(stroke
				(width 0.1)
				(type default)
			)
			(layer "B.Fab")
		)
		(pad "1" smd circle
			(at 0.40005 0 270)
			(size 0 0)
			(layers "B.Cu" "B.Mask" "B.Paste")
			(net "GND")
		)
		(pad "2" smd circle
			(at -0.40005 0 270)
			(size 0 0)
			(layers "B.Cu" "B.Mask" "B.Paste")
			(net "FM_JTAG_BMC_MUX_SEL")
		)
	)
)
